FILE_TYPE = CONNECTIVITY;
{Allegro Design Entry HDL 17.4-2019 S026 (4007227) 1/17/2022}
"PAGE_NUMBER" = 449;
0"NC";
1"P5E_CPU1_P2_RX_BUF_DN<7:0>";
2"P5E_CPU1_P2_RX_BUF_DP<7:0>";
3"P5E_CPU1_P2_RX_BUF_DN<15:8>";
4"P5E_CPU1_P2_RX_BUF_DP<15:8>";
5"P5E_CPU1_P2_RX_BUF_DN<9>";
6"P5E_CPU1_P2_RX_BUF_DN<12>";
7"P5E_CPU1_P2_RX_BUF_DP<13>";
8"P5E_CPU1_P2_RX_BUF_DP<1>";
9"P5E_CPU1_P2_RX_BUF_DP<3>";
10"P5E_CPU1_P2_RX_BUF_DN<4>";
11"P5E_CPU1_P2_RX_BUF_DN<3>";
12"P5E_CPU1_P2_RX_BUF_DN<0>";
13"P5E_CPU1_P2_RX_BUF_DP<6>";
14"P5E_CPU1_P2_RX_BUF_DP<4>";
15"P5E_CPU1_P2_RX_BUF_DP<7>";
16"P5E_CPU1_P2_RX_BUF_DN<5>";
17"P5E_CPU1_P2_RX_BUF_DP<2>";
18"P5E_CPU1_P2_RX_BUF_DP<11>";
19"P5E_CPU1_P2_RX_BUF_DP<12>";
20"P5E_CPU1_P2_RX_BUF_DN<15>";
21"P5E_CPU1_P2_RX_BUF_DP<15>";
22"P5E_CPU1_P2_RX_BUF_DP<8>";
23"P5E_CPU1_P2_RX_BUF_DP<9>";
24"P5E_CPU1_P2_RX_BUF_DN<10>";
25"P5E_CPU1_P2_RX_BUF_DP<10>";
26"P5E_CPU1_P2_RX_BUF_DN<11>";
27"P5E_CPU1_P2_RX_BUF_DN<13>";
28"P5E_CPU1_P2_RX_BUF_DN<14>";
29"P5E_CPU1_P2_RX_BUF_DP<14>";
30"P5E_CPU1_P2_RX_BUF_DN<8>";
31"P5E_CPU1_P2_RX_BUF_DP<5>";
32"P5E_CPU1_P2_RX_BUF_DP<0>";
33"P5E_CPU1_P2_RX_BUF_DN<1>";
34"P5E_CPU1_P2_RX_BUF_DN<2>";
35"P5E_CPU1_P2_RX_BUF_DN<6>";
36"P5E_CPU1_P2_RX_BUF_DN<7>";
%"PT5161LRS"
"1","(-7800,3850)","0","pure_quanta","I1";
;
LOCATION"U6016"
$SEC"1"
CDS_SEC"1"
VALUE"PT5161LRS"
MATERIAL"IC"
PART_TYPE"SMLF"
NEEDS_NO_SIZE"TRUE"
CDS_LMAN_SYM_OUTLINE"-350,1450,300,-1400"
CDS_LIB"pure_quanta"
PART_NUMBER"AJ051610U03";
"A_PERN7"
$PN"CB2"30;
"A_PERP7"
$PN"CD1"22;
"A_PERN6"
$PN"BR2"5;
"A_PERP6"
$PN"BU1"23;
"A_PERN5"
$PN"BH2"24;
"A_PERP5"
$PN"BK1"25;
"A_PERN4"
$PN"BA2"26;
"A_PERP4"
$PN"BC1"18;
"A_PERN3"
$PN"AP2"6;
"A_PERP3"
$PN"AT1"19;
"A_PERN2"
$PN"AG2"27;
"A_PERP2"
$PN"AJ1"7;
"A_PERN1"
$PN"Y2"28;
"A_PERP1"
$PN"AB1"29;
"A_PERN0"
$PN"N2"20;
"A_PERP0"
$PN"R1"21;
%"TAP"
"1","(-6575,3600)","0","standard","I10";
;
CDS_LIB"standard"
BODY_TYPE"PLUMBING"
HDL_TAP"TRUE";
"B \NAC \NWC"3;
"S \NAC"
BN"11"26;
%"TAP"
"1","(-6575,3950)","0","standard","I11";
;
CDS_LIB"standard"
BODY_TYPE"PLUMBING"
HDL_TAP"TRUE";
"B \NAC \NWC"3;
"S \NAC"
BN"12"6;
%"TAP"
"1","(-6775,4400)","0","standard","I12";
;
CDS_LIB"standard"
BODY_TYPE"PLUMBING"
HDL_TAP"TRUE";
"B \NAC \NWC"4;
"S \NAC"
BN"13"7;
%"TAP"
"1","(-6575,4300)","0","standard","I13";
;
CDS_LIB"standard"
BODY_TYPE"PLUMBING"
HDL_TAP"TRUE";
"B \NAC \NWC"3;
"S \NAC"
BN"13"27;
%"TAP"
"1","(-6775,4750)","0","standard","I14";
;
CDS_LIB"standard"
BODY_TYPE"PLUMBING"
HDL_TAP"TRUE";
"B \NAC \NWC"4;
"S \NAC"
BN"14"29;
%"TAP"
"1","(-6575,4650)","0","standard","I15";
;
CDS_LIB"standard"
BODY_TYPE"PLUMBING"
HDL_TAP"TRUE";
"B \NAC \NWC"3;
"S \NAC"
BN"14"28;
%"TAP"
"1","(-6575,5000)","0","standard","I16";
;
CDS_LIB"standard"
BODY_TYPE"PLUMBING"
HDL_TAP"TRUE";
"B \NAC \NWC"3;
"S \NAC"
BN"15"20;
%"TAP"
"1","(-6775,5100)","0","standard","I17";
;
CDS_LIB"standard"
BODY_TYPE"PLUMBING"
HDL_TAP"TRUE";
"B \NAC \NWC"4;
"S \NAC"
BN"15"21;
%"TAP"
"1","(-6775,2650)","0","standard","I2";
;
CDS_LIB"standard"
BODY_TYPE"PLUMBING"
HDL_TAP"TRUE";
"B \NAC \NWC"4;
"S \NAC"
BN"8"22;
%"TAP"
"1","(-2325,2675)","0","standard","I20";
;
CDS_LIB"standard"
BODY_TYPE"PLUMBING"
HDL_TAP"TRUE";
"B \NAC \NWC"2;
"S \NAC"
BN"0"32;
%"TAP"
"1","(-2325,3025)","0","standard","I21";
;
CDS_LIB"standard"
BODY_TYPE"PLUMBING"
HDL_TAP"TRUE";
"B \NAC \NWC"2;
"S \NAC"
BN"1"8;
%"TAP"
"1","(-2325,3375)","0","standard","I22";
;
CDS_LIB"standard"
BODY_TYPE"PLUMBING"
HDL_TAP"TRUE";
"B \NAC \NWC"2;
"S \NAC"
BN"2"17;
%"TAP"
"1","(-2325,3725)","0","standard","I23";
;
CDS_LIB"standard"
BODY_TYPE"PLUMBING"
HDL_TAP"TRUE";
"B \NAC \NWC"2;
"S \NAC"
BN"3"9;
%"TAP"
"1","(-2125,2575)","0","standard","I24";
;
CDS_LIB"standard"
BODY_TYPE"PLUMBING"
HDL_TAP"TRUE";
"B \NAC \NWC"1;
"S \NAC"
BN"0"12;
%"TAP"
"1","(-2125,2925)","0","standard","I25";
;
CDS_LIB"standard"
BODY_TYPE"PLUMBING"
HDL_TAP"TRUE";
"B \NAC \NWC"1;
"S \NAC"
BN"1"33;
%"TAP"
"1","(-2125,3275)","0","standard","I26";
;
CDS_LIB"standard"
BODY_TYPE"PLUMBING"
HDL_TAP"TRUE";
"B \NAC \NWC"1;
"S \NAC"
BN"2"34;
%"TAP"
"1","(-2125,3625)","0","standard","I27";
;
CDS_LIB"standard"
BODY_TYPE"PLUMBING"
HDL_TAP"TRUE";
"B \NAC \NWC"1;
"S \NAC"
BN"3"11;
%"TAP"
"1","(-2125,3975)","0","standard","I28";
;
CDS_LIB"standard"
BODY_TYPE"PLUMBING"
HDL_TAP"TRUE";
"B \NAC \NWC"1;
"S \NAC"
BN"4"10;
%"TAP"
"1","(-2325,4075)","0","standard","I29";
;
CDS_LIB"standard"
BODY_TYPE"PLUMBING"
HDL_TAP"TRUE";
"B \NAC \NWC"2;
"S \NAC"
BN"4"14;
%"TAP"
"1","(-6775,3000)","0","standard","I3";
;
CDS_LIB"standard"
BODY_TYPE"PLUMBING"
HDL_TAP"TRUE";
"B \NAC \NWC"4;
"S \NAC"
BN"9"23;
%"TAP"
"1","(-2325,4425)","0","standard","I30";
;
CDS_LIB"standard"
BODY_TYPE"PLUMBING"
HDL_TAP"TRUE";
"B \NAC \NWC"2;
"S \NAC"
BN"5"31;
%"TAP"
"1","(-2325,4775)","0","standard","I31";
;
CDS_LIB"standard"
BODY_TYPE"PLUMBING"
HDL_TAP"TRUE";
"B \NAC \NWC"2;
"S \NAC"
BN"6"13;
%"TAP"
"1","(-2325,5125)","0","standard","I32";
;
CDS_LIB"standard"
BODY_TYPE"PLUMBING"
HDL_TAP"TRUE";
"B \NAC \NWC"2;
"S \NAC"
BN"7"15;
%"TAP"
"1","(-2125,4325)","0","standard","I33";
;
CDS_LIB"standard"
BODY_TYPE"PLUMBING"
HDL_TAP"TRUE";
"B \NAC \NWC"1;
"S \NAC"
BN"5"16;
%"TAP"
"1","(-2125,4675)","0","standard","I34";
;
CDS_LIB"standard"
BODY_TYPE"PLUMBING"
HDL_TAP"TRUE";
"B \NAC \NWC"1;
"S \NAC"
BN"6"35;
%"TAP"
"1","(-2125,5025)","0","standard","I35";
;
CDS_LIB"standard"
BODY_TYPE"PLUMBING"
HDL_TAP"TRUE";
"B \NAC \NWC"1;
"S \NAC"
BN"7"36;
%"PT5161LRS"
"2","(-3350,3875)","0","pure_quanta","I38";
;
LOCATION"U6016"
$SEC"2"
CDS_SEC"2"
PART_TYPE"SMLF"
MATERIAL"IC"
VALUE"PT5161LRS"
CDS_LIB"pure_quanta"
CDS_LMAN_SYM_OUTLINE"-350,1450,300,-1400"
NEEDS_NO_SIZE"TRUE"
PART_NUMBER"AJ051610U03";
"A_PERN15"
$PN"EV2"12;
"A_PERP15"
$PN"EY1"32;
"A_PERN14"
$PN"EL2"33;
"A_PERP14"
$PN"EN1"8;
"A_PERN13"
$PN"ED2"34;
"A_PERP13"
$PN"EF1"17;
"A_PERN12"
$PN"DU2"11;
"A_PERP12"
$PN"DW1"9;
"A_PERN11"
$PN"DK2"10;
"A_PERP11"
$PN"DM1"14;
"A_PERN10"
$PN"DC2"16;
"A_PERP10"
$PN"DE1"31;
"A_PERN9"
$PN"CT2"35;
"A_PERP9"
$PN"CV1"13;
"A_PERN8"
$PN"CJ2"36;
"A_PERP8"
$PN"CL1"15;
%"TAP"
"1","(-6575,2550)","0","standard","I4";
;
CDS_LIB"standard"
BODY_TYPE"PLUMBING"
HDL_TAP"TRUE";
"B \NAC \NWC"3;
"S \NAC"
BN"8"30;
%"TAP"
"1","(-6575,2900)","0","standard","I5";
;
CDS_LIB"standard"
BODY_TYPE"PLUMBING"
HDL_TAP"TRUE";
"B \NAC \NWC"3;
"S \NAC"
BN"9"5;
%"TAP"
"1","(-6775,3350)","0","standard","I6";
;
CDS_LIB"standard"
BODY_TYPE"PLUMBING"
HDL_TAP"TRUE";
"B \NAC \NWC"4;
"S \NAC"
BN"10"25;
%"TAP"
"1","(-6575,3250)","0","standard","I7";
;
CDS_LIB"standard"
BODY_TYPE"PLUMBING"
HDL_TAP"TRUE";
"B \NAC \NWC"3;
"S \NAC"
BN"10"24;
%"TAP"
"1","(-6775,3700)","0","standard","I8";
;
CDS_LIB"standard"
BODY_TYPE"PLUMBING"
HDL_TAP"TRUE";
"B \NAC \NWC"4;
"S \NAC"
BN"11"18;
%"TAP"
"1","(-6775,4050)","0","standard","I9";
;
CDS_LIB"standard"
BODY_TYPE"PLUMBING"
HDL_TAP"TRUE";
"B \NAC \NWC"4;
"S \NAC"
BN"12"19;
END.
